(kicad_pcb
	(version 20260206)
	(generator "pcbnew")
	(generator_version "10.0")
	(general
		(thickness 1.6)
		(legacy_teardrops no)
	)
	(paper "A4")
	(title_block
		(title "baseboard — 13948-1b.1110WZS1818.brd")
		(comment 1 "Honey Badger (Wiwynn) / footprints 1542-1548 of 2523")
	)
	(layers
		(0 "F.Cu" signal "TOP")
		(4 "In1.Cu" signal "L2GND")
		(6 "In2.Cu" signal "L3")
		(8 "In3.Cu" signal "L4VCC")
		(10 "In4.Cu" signal "L5VCC")
		(12 "In5.Cu" signal "L6")
		(14 "In6.Cu" signal "L7GND")
		(2 "B.Cu" signal "BOTTOM")
		(9 "F.Adhes" user "F.Adhesive")
		(11 "B.Adhes" user "B.Adhesive")
		(13 "F.Paste" user "Package Geometry/Pastemask Top")
		(15 "B.Paste" user "Package Geometry/Pastemask Bottom")
		(5 "F.SilkS" user "Ref Des/Silkscreen Top")
		(7 "B.SilkS" user "Ref Des/Silkscreen Bottom")
		(1 "F.Mask" user "Board Geometry/Soldermask Top")
		(3 "B.Mask" user "Board Geometry/Soldermask Bottom")
		(17 "Dwgs.User" user "User.Drawings")
		(19 "Cmts.User" user "User.Comments")
		(21 "Eco1.User" user "User.Eco1")
		(23 "Eco2.User" user "User.Eco2")
		(25 "Edge.Cuts" user "Board Geometry/Outline")
		(27 "Margin" user)
		(31 "F.CrtYd" user "Package Geometry/Place Bound Top")
		(29 "B.CrtYd" user "Package Geometry/Place Bound Bottom")
		(35 "F.Fab" user "Ref Des/Assembly Top")
		(33 "B.Fab" user "Ref Des/Assembly Bottom")
	)
	(footprint ""
		(layer "F.Cu")
		(at 337.566 -74.422 -90)
		(property "Reference" "R681"
			(at 0 0 270)
			(layer "F.SilkS")
			(hide yes)
			(effects
				(font
					(size 1.27 1.27)
				)
			)
		)
		(property "Value" "0R2J-2-GP"
			(at 0.064008 -3.993896 270)
			(unlocked yes)
			(layer "F.Fab")
			(hide yes)
			(effects
				(font
					(size 1.016 1.016)
					(thickness 0.1524)
				)
			)
		)
		(property "Device Type" "R402H16"
			(at 0.064008 -5.517896 270)
			(unlocked yes)
			(layer "F.Fab")
			(hide yes)
			(effects
				(font
					(size 1.016 1.016)
					(thickness 0.1524)
				)
			)
		)
		(duplicate_pad_numbers_are_jumpers no)
		(fp_line
			(start -0.508 -0.9398)
			(end -0.508 0.9398)
			(stroke
				(width 0.1524)
				(type default)
			)
			(layer "F.SilkS")
		)
		(fp_line
			(start 0.508 -0.9398)
			(end -0.508 -0.9398)
			(stroke
				(width 0.1524)
				(type default)
			)
			(layer "F.SilkS")
		)
		(fp_rect
			(start -0.508 0.9398)
			(end 0.508 -0.9398)
			(stroke
				(width 0)
				(type default)
			)
			(fill no)
			(layer "F.CrtYd")
		)
		(fp_rect
			(start -0.508 0.9398)
			(end 0.508 -0.9398)
			(stroke
				(width 0)
				(type default)
			)
			(fill no)
			(layer "F.Fab")
		)
		(pad "1" smd custom
			(at 0 -0.4445 270)
			(size 0.1397 0.1397)
			(layers "F.Cu" "F.Mask" "F.Paste")
			(net "ROMD0_R")
			(options
				(clearance outline)
				(anchor circle)
			)
			(primitives
				(gr_poly
					(pts
						(arc
							(start -0.1778 -0.2794)
							(mid -0.249642 -0.249642)
							(end -0.2794 -0.1778)
						)
						(arc
							(start -0.2794 0.1778)
							(mid -0.249642 0.249642)
							(end -0.1778 0.2794)
						)
						(arc
							(start 0.1778 0.2794)
							(mid 0.249642 0.249642)
							(end 0.2794 0.1778)
						)
						(arc
							(start 0.2794 -0.1778)
							(mid 0.249642 -0.249642)
							(end 0.1778 -0.2794)
						)
					)
					(width 0)
					(fill yes)
				)
			)
		)
		(pad "2" smd custom
			(at 0 0.4445 270)
			(size 0.1397 0.1397)
			(layers "F.Cu" "F.Mask" "F.Paste")
			(net "ROMD0_R_R")
			(options
				(clearance outline)
				(anchor circle)
			)
			(primitives
				(gr_poly
					(pts
						(arc
							(start -0.1778 -0.2794)
							(mid -0.249642 -0.249642)
							(end -0.2794 -0.1778)
						)
						(arc
							(start -0.2794 0.1778)
							(mid -0.249642 0.249642)
							(end -0.1778 0.2794)
						)
						(arc
							(start 0.1778 0.2794)
							(mid 0.249642 0.249642)
							(end 0.2794 0.1778)
						)
						(arc
							(start 0.2794 -0.1778)
							(mid 0.249642 -0.249642)
							(end 0.1778 -0.2794)
						)
					)
					(width 0)
					(fill yes)
				)
			)
		)
	)
	(footprint ""
		(layer "F.Cu")
		(at 143.256 -38.862 180)
		(property "Reference" "SR703"
			(at 0 0 180)
			(layer "F.SilkS")
			(hide yes)
			(effects
				(font
					(size 1.27 1.27)
				)
			)
		)
		(property "Value" "10KR2F-2-GP"
			(at 0.064008 -3.993896 180)
			(unlocked yes)
			(layer "F.Fab")
			(hide yes)
			(effects
				(font
					(size 1.016 1.016)
					(thickness 0.1524)
				)
			)
		)
		(property "Device Type" "R402H16"
			(at 0.064008 -5.517896 180)
			(unlocked yes)
			(layer "F.Fab")
			(hide yes)
			(effects
				(font
					(size 1.016 1.016)
					(thickness 0.1524)
				)
			)
		)
		(duplicate_pad_numbers_are_jumpers no)
		(fp_line
			(start 0.508 -0.9398)
			(end -0.508 -0.9398)
			(stroke
				(width 0.1524)
				(type default)
			)
			(layer "F.SilkS")
		)
		(fp_line
			(start -0.508 -0.9398)
			(end -0.508 0.9398)
			(stroke
				(width 0.1524)
				(type default)
			)
			(layer "F.SilkS")
		)
		(fp_rect
			(start -0.508 0.9398)
			(end 0.508 -0.9398)
			(stroke
				(width 0)
				(type default)
			)
			(fill no)
			(layer "F.CrtYd")
		)
		(fp_rect
			(start -0.508 0.9398)
			(end 0.508 -0.9398)
			(stroke
				(width 0)
				(type default)
			)
			(fill no)
			(layer "F.Fab")
		)
		(pad "1" smd custom
			(at 0 -0.4445 180)
			(size 0.1397 0.1397)
			(layers "F.Cu" "F.Mask" "F.Paste")
			(net "P1V8_C")
			(options
				(clearance outline)
				(anchor circle)
			)
			(primitives
				(gr_poly
					(pts
						(arc
							(start -0.1778 -0.2794)
							(mid -0.249642 -0.249642)
							(end -0.2794 -0.1778)
						)
						(arc
							(start -0.2794 0.1778)
							(mid -0.249642 0.249642)
							(end -0.1778 0.2794)
						)
						(arc
							(start 0.1778 0.2794)
							(mid 0.249642 0.249642)
							(end 0.2794 0.1778)
						)
						(arc
							(start 0.2794 -0.1778)
							(mid 0.249642 -0.249642)
							(end 0.1778 -0.2794)
						)
					)
					(width 0)
					(fill yes)
				)
			)
		)
		(pad "2" smd custom
			(at 0 0.4445 180)
			(size 0.1397 0.1397)
			(layers "F.Cu" "F.Mask" "F.Paste")
			(net "IOC_WP_N")
			(options
				(clearance outline)
				(anchor circle)
			)
			(primitives
				(gr_poly
					(pts
						(arc
							(start -0.1778 -0.2794)
							(mid -0.249642 -0.249642)
							(end -0.2794 -0.1778)
						)
						(arc
							(start -0.2794 0.1778)
							(mid -0.249642 0.249642)
							(end -0.1778 0.2794)
						)
						(arc
							(start 0.1778 0.2794)
							(mid 0.249642 0.249642)
							(end 0.2794 0.1778)
						)
						(arc
							(start 0.2794 -0.1778)
							(mid 0.249642 -0.249642)
							(end 0.1778 -0.2794)
						)
					)
					(width 0)
					(fill yes)
				)
			)
		)
	)
	(footprint ""
		(layer "F.Cu")
		(at 75.057 -32.385 180)
		(property "Reference" "SR716"
			(at 0 0 180)
			(layer "F.SilkS")
			(hide yes)
			(effects
				(font
					(size 1.27 1.27)
				)
			)
		)
		(property "Value" "D51R3F-2-GP"
			(at -0.0254 -2.5146 180)
			(unlocked yes)
			(layer "F.Fab")
			(hide yes)
			(effects
				(font
					(size 1.016 1.016)
					(thickness 0.1524)
				)
			)
		)
		(property "Device Type" "R603H22"
			(at -0.0254 -4.0386 180)
			(unlocked yes)
			(layer "F.Fab")
			(hide yes)
			(effects
				(font
					(size 1.016 1.016)
					(thickness 0.1524)
				)
			)
		)
		(duplicate_pad_numbers_are_jumpers no)
		(fp_line
			(start 0.2032 0)
			(end 0.4826 0)
			(stroke
				(width 0.2032)
				(type default)
			)
			(layer "F.SilkS")
		)
		(fp_line
			(start -0.4826 0)
			(end -0.2032 0)
			(stroke
				(width 0.2032)
				(type default)
			)
			(layer "F.SilkS")
		)
		(fp_rect
			(start -0.5842 1.3335)
			(end 0.5842 -1.3335)
			(stroke
				(width 0)
				(type default)
			)
			(fill no)
			(layer "F.CrtYd")
		)
		(fp_rect
			(start -0.5842 1.3335)
			(end 0.5842 -1.3335)
			(stroke
				(width 0)
				(type default)
			)
			(fill no)
			(layer "F.Fab")
		)
		(pad "1" smd custom
			(at 0 -0.762 180)
			(size 0.2159 0.2159)
			(layers "F.Cu" "F.Mask" "F.Paste")
			(net "P0V955_C")
			(options
				(clearance outline)
				(anchor circle)
			)
			(primitives
				(gr_poly
					(pts
						(arc
							(start -0.3302 -0.4318)
							(mid -0.402042 -0.402042)
							(end -0.4318 -0.3302)
						)
						(arc
							(start -0.4318 0.3302)
							(mid -0.402042 0.402042)
							(end -0.3302 0.4318)
						)
						(arc
							(start 0.3302 0.4318)
							(mid 0.402042 0.402042)
							(end 0.4318 0.3302)
						)
						(arc
							(start 0.4318 -0.3302)
							(mid 0.402042 -0.402042)
							(end 0.3302 -0.4318)
						)
					)
					(width 0)
					(fill yes)
				)
			)
		)
		(pad "2" smd custom
			(at 0 0.762 180)
			(size 0.2159 0.2159)
			(layers "F.Cu" "F.Mask" "F.Paste")
			(net "SAS0_AVDD")
			(options
				(clearance outline)
				(anchor circle)
			)
			(primitives
				(gr_poly
					(pts
						(arc
							(start -0.3302 -0.4318)
							(mid -0.402042 -0.402042)
							(end -0.4318 -0.3302)
						)
						(arc
							(start -0.4318 0.3302)
							(mid -0.402042 0.402042)
							(end -0.3302 0.4318)
						)
						(arc
							(start 0.3302 0.4318)
							(mid 0.402042 0.402042)
							(end 0.4318 0.3302)
						)
						(arc
							(start 0.4318 -0.3302)
							(mid 0.402042 -0.402042)
							(end 0.3302 -0.4318)
						)
					)
					(width 0)
					(fill yes)
				)
			)
		)
	)
	(footprint ""
		(layer "F.Cu")
		(at 220.345 -158.242 180)
		(property "Reference" "R577"
			(at 0 0 180)
			(layer "F.SilkS")
			(hide yes)
			(effects
				(font
					(size 1.27 1.27)
				)
			)
		)
		(property "Value" "10KR2F-2-GP"
			(at 0.064008 -3.993896 180)
			(unlocked yes)
			(layer "F.Fab")
			(hide yes)
			(effects
				(font
					(size 1.016 1.016)
					(thickness 0.1524)
				)
			)
		)
		(property "Device Type" "R402H16"
			(at 0.064008 -5.517896 180)
			(unlocked yes)
			(layer "F.Fab")
			(hide yes)
			(effects
				(font
					(size 1.016 1.016)
					(thickness 0.1524)
				)
			)
		)
		(duplicate_pad_numbers_are_jumpers no)
		(fp_line
			(start 0.508 -0.9398)
			(end -0.508 -0.9398)
			(stroke
				(width 0.1524)
				(type default)
			)
			(layer "F.SilkS")
		)
		(fp_line
			(start -0.508 -0.9398)
			(end -0.508 0.9398)
			(stroke
				(width 0.1524)
				(type default)
			)
			(layer "F.SilkS")
		)
		(fp_rect
			(start -0.508 0.9398)
			(end 0.508 -0.9398)
			(stroke
				(width 0)
				(type default)
			)
			(fill no)
			(layer "F.CrtYd")
		)
		(fp_rect
			(start -0.508 0.9398)
			(end 0.508 -0.9398)
			(stroke
				(width 0)
				(type default)
			)
			(fill no)
			(layer "F.Fab")
		)
		(pad "1" smd custom
			(at 0 -0.4445 180)
			(size 0.1397 0.1397)
			(layers "F.Cu" "F.Mask" "F.Paste")
			(net "P3V3_STBY")
			(options
				(clearance outline)
				(anchor circle)
			)
			(primitives
				(gr_poly
					(pts
						(arc
							(start -0.1778 -0.2794)
							(mid -0.249642 -0.249642)
							(end -0.2794 -0.1778)
						)
						(arc
							(start -0.2794 0.1778)
							(mid -0.249642 0.249642)
							(end -0.1778 0.2794)
						)
						(arc
							(start 0.1778 0.2794)
							(mid 0.249642 0.249642)
							(end 0.2794 0.1778)
						)
						(arc
							(start 0.2794 -0.1778)
							(mid 0.249642 -0.249642)
							(end 0.1778 -0.2794)
						)
					)
					(width 0)
					(fill yes)
				)
			)
		)
		(pad "2" smd custom
			(at 0 0.4445 180)
			(size 0.1397 0.1397)
			(layers "F.Cu" "F.Mask" "F.Paste")
			(net "JTAG_DT")
			(options
				(clearance outline)
				(anchor circle)
			)
			(primitives
				(gr_poly
					(pts
						(arc
							(start -0.1778 -0.2794)
							(mid -0.249642 -0.249642)
							(end -0.2794 -0.1778)
						)
						(arc
							(start -0.2794 0.1778)
							(mid -0.249642 0.249642)
							(end -0.1778 0.2794)
						)
						(arc
							(start 0.1778 0.2794)
							(mid 0.249642 0.249642)
							(end 0.2794 0.1778)
						)
						(arc
							(start 0.2794 -0.1778)
							(mid 0.249642 -0.249642)
							(end 0.1778 -0.2794)
						)
					)
					(width 0)
					(fill yes)
				)
			)
		)
	)
	(footprint ""
		(layer "F.Cu")
		(at 81.539842 -139.771882 180)
		(property "Reference" "SC1120"
			(at 0 0 180)
			(layer "F.SilkS")
			(hide yes)
			(effects
				(font
					(size 1.27 1.27)
				)
			)
		)
		(property "Value" "SCD1U16V2KX-3GP"
			(at 1.1811 -2.7051 180)
			(unlocked yes)
			(layer "F.Fab")
			(hide yes)
			(effects
				(font
					(size 1.016 1.016)
					(thickness 0.1524)
				)
			)
		)
		(property "Device Type" "C402H22"
			(at 1.1811 -4.2291 180)
			(unlocked yes)
			(layer "F.Fab")
			(hide yes)
			(effects
				(font
					(size 1.016 1.016)
					(thickness 0.1524)
				)
			)
		)
		(duplicate_pad_numbers_are_jumpers no)
		(fp_rect
			(start -0.4318 0.9525)
			(end 0.4318 -0.9525)
			(stroke
				(width 0)
				(type default)
			)
			(fill no)
			(layer "F.CrtYd")
		)
		(fp_rect
			(start -0.4318 0.9525)
			(end 0.4318 -0.9525)
			(stroke
				(width 0)
				(type default)
			)
			(fill no)
			(layer "F.Fab")
		)
		(pad "1" smd custom
			(at 0 -0.4445 180)
			(size 0.1524 0.1524)
			(layers "F.Cu" "F.Mask" "F.Paste")
			(net "P3V3_STBY")
			(options
				(clearance outline)
				(anchor circle)
			)
			(primitives
				(gr_poly
					(pts
						(arc
							(start 0.3048 -0.2032)
							(mid 0.275042 -0.275042)
							(end 0.2032 -0.3048)
						)
						(arc
							(start -0.2032 -0.3048)
							(mid -0.275042 -0.275042)
							(end -0.3048 -0.2032)
						)
						(arc
							(start -0.3048 0.2032)
							(mid -0.275042 0.275042)
							(end -0.2032 0.3048)
						)
						(arc
							(start 0.2032 0.3048)
							(mid 0.275042 0.275042)
							(end 0.3048 0.2032)
						)
					)
					(width 0)
					(fill yes)
				)
			)
		)
		(pad "2" smd custom
			(at 0 0.4445 180)
			(size 0.1524 0.1524)
			(layers "F.Cu" "F.Mask" "F.Paste")
			(net "GND")
			(options
				(clearance outline)
				(anchor circle)
			)
			(primitives
				(gr_poly
					(pts
						(arc
							(start 0.3048 -0.2032)
							(mid 0.275042 -0.275042)
							(end 0.2032 -0.3048)
						)
						(arc
							(start -0.2032 -0.3048)
							(mid -0.275042 -0.275042)
							(end -0.3048 -0.2032)
						)
						(arc
							(start -0.3048 0.2032)
							(mid -0.275042 0.275042)
							(end -0.2032 0.3048)
						)
						(arc
							(start 0.2032 0.3048)
							(mid 0.275042 0.275042)
							(end 0.3048 0.2032)
						)
					)
					(width 0)
					(fill yes)
				)
			)
		)
	)
	(footprint ""
		(layer "F.Cu")
		(at 223.647 -85.979 90)
		(property "Reference" "SR925"
			(at 0 0 90)
			(layer "F.SilkS")
			(hide yes)
			(effects
				(font
					(size 1.27 1.27)
				)
			)
		)
		(property "Value" "0R2J-2-GP"
			(at 0.064008 -3.993896 90)
			(unlocked yes)
			(layer "F.Fab")
			(hide yes)
			(effects
				(font
					(size 1.016 1.016)
					(thickness 0.1524)
				)
			)
		)
		(property "Device Type" "R402H16"
			(at 0.064008 -5.517896 90)
			(unlocked yes)
			(layer "F.Fab")
			(hide yes)
			(effects
				(font
					(size 1.016 1.016)
					(thickness 0.1524)
				)
			)
		)
		(duplicate_pad_numbers_are_jumpers no)
		(fp_line
			(start 0.508 -0.9398)
			(end -0.508 -0.9398)
			(stroke
				(width 0.1524)
				(type default)
			)
			(layer "F.SilkS")
		)
		(fp_line
			(start -0.508 -0.9398)
			(end -0.508 0.9398)
			(stroke
				(width 0.1524)
				(type default)
			)
			(layer "F.SilkS")
		)
		(fp_rect
			(start -0.508 0.9398)
			(end 0.508 -0.9398)
			(stroke
				(width 0)
				(type default)
			)
			(fill no)
			(layer "F.CrtYd")
		)
		(fp_rect
			(start -0.508 0.9398)
			(end 0.508 -0.9398)
			(stroke
				(width 0)
				(type default)
			)
			(fill no)
			(layer "F.Fab")
		)
		(pad "1" smd custom
			(at 0 -0.4445 90)
			(size 0.1397 0.1397)
			(layers "F.Cu" "F.Mask" "F.Paste")
			(net "IOC_UART_0_TX_R")
			(options
				(clearance outline)
				(anchor circle)
			)
			(primitives
				(gr_poly
					(pts
						(arc
							(start -0.1778 -0.2794)
							(mid -0.249642 -0.249642)
							(end -0.2794 -0.1778)
						)
						(arc
							(start -0.2794 0.1778)
							(mid -0.249642 0.249642)
							(end -0.1778 0.2794)
						)
						(arc
							(start 0.1778 0.2794)
							(mid 0.249642 0.249642)
							(end 0.2794 0.1778)
						)
						(arc
							(start 0.2794 -0.1778)
							(mid 0.249642 -0.249642)
							(end 0.1778 -0.2794)
						)
					)
					(width 0)
					(fill yes)
				)
			)
		)
		(pad "2" smd custom
			(at 0 0.4445 90)
			(size 0.1397 0.1397)
			(layers "F.Cu" "F.Mask" "F.Paste")
			(net "IOC_UART_0_TX")
			(options
				(clearance outline)
				(anchor circle)
			)
			(primitives
				(gr_poly
					(pts
						(arc
							(start -0.1778 -0.2794)
							(mid -0.249642 -0.249642)
							(end -0.2794 -0.1778)
						)
						(arc
							(start -0.2794 0.1778)
							(mid -0.249642 0.249642)
							(end -0.1778 0.2794)
						)
						(arc
							(start 0.1778 0.2794)
							(mid 0.249642 0.249642)
							(end 0.2794 0.1778)
						)
						(arc
							(start 0.2794 -0.1778)
							(mid 0.249642 -0.249642)
							(end 0.1778 -0.2794)
						)
					)
					(width 0)
					(fill yes)
				)
			)
		)
	)
	(footprint ""
		(layer "F.Cu")
		(at 320.0654 -214.4014 90)
		(property "Reference" "Q16"
			(at 0 0 90)
			(layer "F.SilkS")
			(hide yes)
			(effects
				(font
					(size 1.27 1.27)
				)
			)
		)
		(property "Value" "2N7002A-7-GP"
			(at 0.127 -8.9662 90)
			(unlocked yes)
			(layer "F.Fab")
			(hide yes)
			(effects
				(font
					(size 1.016 1.016)
					(thickness 0.1524)
				)
			)
		)
		(property "Device Type" "SOT23DGS2D4H48"
			(at 0.127 -10.4902 90)
			(unlocked yes)
			(layer "F.Fab")
			(hide yes)
			(effects
				(font
					(size 1.016 1.016)
					(thickness 0.1524)
				)
			)
		)
		(duplicate_pad_numbers_are_jumpers no)
		(fp_line
			(start 1.651 -1.778)
			(end -1.651 -1.778)
			(stroke
				(width 0.1524)
				(type default)
			)
			(layer "F.SilkS")
		)
		(fp_line
			(start -1.651 -1.778)
			(end -1.651 1.778)
			(stroke
				(width 0.1524)
				(type default)
			)
			(layer "F.SilkS")
		)
		(fp_line
			(start 1.651 1.778)
			(end 1.651 -1.778)
			(stroke
				(width 0.1524)
				(type default)
			)
			(layer "F.SilkS")
		)
		(fp_line
			(start -1.651 1.778)
			(end 1.651 1.778)
			(stroke
				(width 0.1524)
				(type default)
			)
			(layer "F.SilkS")
		)
		(fp_poly
			(pts
				(xy -1.778 1.8796) (xy -1.778 -1.8796) (xy 1.778 -1.8796) (xy 1.778 1.8796)
			)
			(stroke
				(width 0)
				(type default)
			)
			(fill no)
			(layer "F.CrtYd")
		)
		(fp_poly
			(pts
				(xy -1.778 1.8796) (xy -1.778 -1.8796) (xy 1.778 -1.8796) (xy 1.778 1.8796)
			)
			(stroke
				(width 0)
				(type default)
			)
			(fill no)
			(layer "F.Fab")
		)
		(pad "D" smd custom
			(at 0 -0.9525 90)
			(size 0.1905 0.1905)
			(layers "F.Cu" "F.Mask" "F.Paste")
			(net "EXP_TDO_EN")
			(options
				(clearance outline)
				(anchor circle)
			)
			(primitives
				(gr_poly
					(pts
						(arc
							(start -0.1778 0.5715)
							(mid -0.321484 0.511984)
							(end -0.381 0.3683)
						)
						(arc
							(start -0.381 -0.3683)
							(mid -0.321484 -0.511984)
							(end -0.1778 -0.5715)
						)
						(arc
							(start 0.1778 -0.5715)
							(mid 0.321484 -0.511984)
							(end 0.381 -0.3683)
						)
						(arc
							(start 0.381 0.3683)
							(mid 0.321484 0.511984)
							(end 0.1778 0.5715)
						)
					)
					(width 0)
					(fill yes)
				)
			)
		)
		(pad "G" smd custom
			(at -0.98425 0.9525 90)
			(size 0.1905 0.1905)
			(layers "F.Cu" "F.Mask" "F.Paste")
			(net "BMC_JTAG_L_EN")
			(options
				(clearance outline)
				(anchor circle)
			)
			(primitives
				(gr_poly
					(pts
						(arc
							(start -0.1778 0.5715)
							(mid -0.321484 0.511984)
							(end -0.381 0.3683)
						)
						(arc
							(start -0.381 -0.3683)
							(mid -0.321484 -0.511984)
							(end -0.1778 -0.5715)
						)
						(arc
							(start 0.1778 -0.5715)
							(mid 0.321484 -0.511984)
							(end 0.381 -0.3683)
						)
						(arc
							(start 0.381 0.3683)
							(mid 0.321484 0.511984)
							(end 0.1778 0.5715)
						)
					)
					(width 0)
					(fill yes)
				)
			)
		)
		(pad "S" smd custom
			(at 0.98425 0.9525 90)
			(size 0.1905 0.1905)
			(layers "F.Cu" "F.Mask" "F.Paste")
			(net "GND")
			(options
				(clearance outline)
				(anchor circle)
			)
			(primitives
				(gr_poly
					(pts
						(arc
							(start -0.1778 0.5715)
							(mid -0.321484 0.511984)
							(end -0.381 0.3683)
						)
						(arc
							(start -0.381 -0.3683)
							(mid -0.321484 -0.511984)
							(end -0.1778 -0.5715)
						)
						(arc
							(start 0.1778 -0.5715)
							(mid 0.321484 -0.511984)
							(end 0.381 -0.3683)
						)
						(arc
							(start 0.381 0.3683)
							(mid 0.321484 0.511984)
							(end 0.1778 0.5715)
						)
					)
					(width 0)
					(fill yes)
				)
			)
		)
	)
)
